(kicad_pcb
	(version 20241229)
	(generator "pcbnew")
	(generator_version "9.0")
	(general
		(thickness 1.552)
		(legacy_teardrops no)
	)
	(paper "A4")
	(title_block
		(date "2023-07-25")
		(rev "1.1.4")
		(comment 9 "footprints 25-28 of 379")
	)
	(layers
		(0 "F.Cu" signal)
		(4 "In1.Cu" signal)
		(6 "In2.Cu" signal)
		(8 "In3.Cu" signal)
		(10 "In4.Cu" signal)
		(12 "In5.Cu" signal)
		(14 "In6.Cu" signal)
		(2 "B.Cu" signal)
		(9 "F.Adhes" user "F.Adhesive")
		(11 "B.Adhes" user "B.Adhesive")
		(13 "F.Paste" user)
		(15 "B.Paste" user)
		(5 "F.SilkS" user "F.Silkscreen")
		(7 "B.SilkS" user "B.Silkscreen")
		(1 "F.Mask" user)
		(3 "B.Mask" user)
		(17 "Dwgs.User" user "User.Drawings")
		(19 "Cmts.User" user "User.Comments")
		(21 "Eco1.User" user "User.Eco1")
		(23 "Eco2.User" user "User.Eco2")
		(25 "Edge.Cuts" user)
		(27 "Margin" user)
		(31 "F.CrtYd" user "F.Courtyard")
		(29 "B.CrtYd" user "B.Courtyard")
		(35 "F.Fab" user)
		(33 "B.Fab" user)
	)
	(footprint "antmicro-footprints:LED_0603_1608Metric_G"
		(layer "F.Cu")
		(at 172.63 82.55 180)
		(descr "LED SMD 0603 Green")
		(tags "LED SMD 0603 Green")
		(property "Reference" "D10"
			(at -1.4 1.01 90)
			(layer "F.SilkS")
			(effects
				(font
					(size 0.65 0.65)
					(thickness 0.15)
				)
				(justify right top)
			)
		)
		(property "Value" "LED_G_0603_LTST-C190GKT"
			(at 0 1.6 0)
			(layer "F.Fab")
			(hide yes)
			(effects
				(font
					(size 0.7 0.7)
					(thickness 0.15)
				)
				(justify right top)
			)
		)
		(property "Datasheet" "https://media.digikey.com/pdf/Data%20Sheets/Lite-On%20PDFs/LTST-C190GKT.pdf"
			(at 0 0 0)
			(layer "F.Fab")
			(hide yes)
			(effects
				(font
					(size 1.27 1.27)
					(thickness 0.15)
				)
			)
		)
		(property "Description" "LED, Green, SMD, 0603, 20 mA, 2.1 V, 569 nm"
			(at 0 0 0)
			(layer "F.Fab")
			(hide yes)
			(effects
				(font
					(size 1.27 1.27)
					(thickness 0.15)
				)
			)
		)
		(property "Author" "Antmicro"
			(at 0 0 0)
			(layer "F.Fab")
			(hide yes)
			(effects
				(font
					(size 1 1)
					(thickness 0.15)
				)
			)
		)
		(property "License" "Apache-2.0"
			(at 0 0 0)
			(layer "F.Fab")
			(hide yes)
			(effects
				(font
					(size 1 1)
					(thickness 0.15)
				)
			)
		)
		(property "MPN" "LTST-C190GKT"
			(at 0 0 0)
			(layer "F.Fab")
			(hide yes)
			(effects
				(font
					(size 1 1)
					(thickness 0.15)
				)
			)
		)
		(property "Manufacturer" "Lite-On"
			(at 0 0 0)
			(layer "F.Fab")
			(hide yes)
			(effects
				(font
					(size 1 1)
					(thickness 0.15)
				)
			)
		)
		(property "Color" "Green"
			(at 0 0 180)
			(unlocked yes)
			(layer "F.Fab")
			(hide yes)
			(effects
				(font
					(size 1 1)
					(thickness 0.15)
				)
			)
		)
		(sheetname "/Peripherals/")
		(sheetfile "peripherals.kicad_sch")
		(attr smd)
		(fp_line
			(start 0.22 0.35)
			(end -0.22 0.35)
			(stroke
				(width 0.15)
				(type solid)
			)
			(layer "F.SilkS")
		)
		(fp_line
			(start 0.22 -0.35)
			(end -0.22 -0.35)
			(stroke
				(width 0.15)
				(type solid)
			)
			(layer "F.SilkS")
		)
		(fp_line
			(start 0.105328 0.201008)
			(end 0.105328 -0.198992)
			(stroke
				(width 0.1)
				(type solid)
			)
			(layer "F.SilkS")
		)
		(fp_line
			(start 0.105328 0.201008)
			(end -0.094672 0.001008)
			(stroke
				(width 0.1)
				(type solid)
			)
			(layer "F.SilkS")
		)
		(fp_line
			(start 0.105328 0.001008)
			(end 0.24 0.001)
			(stroke
				(width 0.1)
				(type solid)
			)
			(layer "F.SilkS")
		)
		(fp_line
			(start -0.094672 0.201008)
			(end -0.094672 -0.198992)
			(stroke
				(width 0.1)
				(type solid)
			)
			(layer "F.SilkS")
		)
		(fp_line
			(start -0.094672 0.001008)
			(end 0.105328 -0.198992)
			(stroke
				(width 0.1)
				(type solid)
			)
			(layer "F.SilkS")
		)
		(fp_line
			(start -0.094672 0.001008)
			(end -0.24 0.001008)
			(stroke
				(width 0.1)
				(type solid)
			)
			(layer "F.SilkS")
		)
		(fp_line
			(start -1.18 -0.319)
			(end -1.18 0.321)
			(stroke
				(width 0.15)
				(type solid)
			)
			(layer "F.SilkS")
		)
		(fp_rect
			(start 1.25 0.65)
			(end -1.25 -0.65)
			(stroke
				(width 0.05)
				(type solid)
			)
			(fill no)
			(layer "F.CrtYd")
		)
		(fp_line
			(start 0.599 0)
			(end 0.201 0)
			(stroke
				(width 0.15)
				(type solid)
			)
			(layer "F.Fab")
		)
		(fp_line
			(start 0.201 0.2)
			(end 0.201 0)
			(stroke
				(width 0.15)
				(type solid)
			)
			(layer "F.Fab")
		)
		(fp_line
			(start 0.201 0)
			(end 0.201 -0.202)
			(stroke
				(width 0.15)
				(type solid)
			)
			(layer "F.Fab")
		)
		(fp_line
			(start 0.201 -0.202)
			(end -0.101 0)
			(stroke
				(width 0.15)
				(type solid)
			)
			(layer "F.Fab")
		)
		(fp_line
			(start -0.101 0)
			(end 0.201 0.2)
			(stroke
				(width 0.15)
				(type solid)
			)
			(layer "F.Fab")
		)
		(fp_line
			(start -0.199 0.2)
			(end -0.199 0.1)
			(stroke
				(width 0.15)
				(type solid)
			)
			(layer "F.Fab")
		)
		(fp_line
			(start -0.199 0)
			(end -0.597 0)
			(stroke
				(width 0.15)
				(type solid)
			)
			(layer "F.Fab")
		)
		(fp_line
			(start -0.199 -0.202)
			(end -0.199 0.1)
			(stroke
				(width 0.15)
				(type solid)
			)
			(layer "F.Fab")
		)
		(fp_rect
			(start 0.848 0.4)
			(end -0.85 -0.402)
			(stroke
				(width 0.15)
				(type solid)
			)
			(fill no)
			(layer "F.Fab")
		)
		(fp_text user "License: Apache-2.0"
			(at -1.4224 3.599 0)
			(layer "F.Fab")
			(effects
				(font
					(size 0.7 0.7)
					(thickness 0.15)
				)
				(justify right top)
			)
		)
		(fp_text user "Author: Antmicro"
			(at -1.4224 4.799 0)
			(layer "F.Fab")
			(effects
				(font
					(size 0.7 0.7)
					(thickness 0.15)
				)
				(justify right top)
			)
		)
		(fp_text user "${REFERENCE}"
			(at -1.4224 5.999 0)
			(layer "F.Fab")
			(effects
				(font
					(size 0.7 0.7)
					(thickness 0.15)
				)
				(justify right top)
			)
		)
		(pad "1" smd roundrect
			(at -0.7 0)
			(size 0.8 1)
			(layers "F.Cu" "F.Mask" "F.Paste")
			(roundrect_rratio 0.2)
			(net 1 "GND")
			(pinfunction "C")
			(pintype "passive")
		)
		(pad "2" smd roundrect
			(at 0.7 0)
			(size 0.8 1)
			(layers "F.Cu" "F.Mask" "F.Paste")
			(roundrect_rratio 0.2)
			(net 256 "Net-(D10-A)")
			(pinfunction "A")
			(pintype "passive")
		)
	)
	(footprint "antmicro-footprints:TSOT23-6"
		(layer "F.Cu")
		(at 164.461 66.097)
		(property "Reference" "U7"
			(at 1.849 1.443 0)
			(layer "F.SilkS")
			(effects
				(font
					(size 0.65 0.65)
					(thickness 0.15)
				)
				(justify left bottom)
			)
		)
		(property "Value" "AP62301WU-7"
			(at -0.005 2.6 0)
			(layer "F.Fab")
			(hide yes)
			(effects
				(font
					(size 0.7 0.7)
					(thickness 0.15)
				)
				(justify left bottom)
			)
		)
		(property "Datasheet" "https://www.diodes.com/assets/Datasheets/AP62300_AP62301_AP62300T.pdf"
			(at 0 0 0)
			(layer "F.Fab")
			(hide yes)
			(effects
				(font
					(size 1.27 1.27)
					(thickness 0.15)
				)
			)
		)
		(property "Description" "DC-DC Switching Synchronous Buck Regulator, Adjustable, 4.2V-18Vin, 0.8V-7V/3A out, TSOT-26-6"
			(at 0 0 0)
			(layer "F.Fab")
			(hide yes)
			(effects
				(font
					(size 1.27 1.27)
					(thickness 0.15)
				)
			)
		)
		(property "Author" "Antmicro"
			(at 98.39 230.59 90)
			(layer "F.Fab")
			(hide yes)
			(effects
				(font
					(size 1 1)
					(thickness 0.15)
				)
			)
		)
		(property "License" "Apache-2.0"
			(at 98.39 230.59 90)
			(layer "F.Fab")
			(hide yes)
			(effects
				(font
					(size 1 1)
					(thickness 0.15)
				)
			)
		)
		(property "MPN" "AP62301WU-7"
			(at 98.39 230.59 90)
			(layer "F.Fab")
			(hide yes)
			(effects
				(font
					(size 1 1)
					(thickness 0.15)
				)
			)
		)
		(property "Manufacturer" "Diodes Incorporated"
			(at 98.39 230.59 90)
			(layer "F.Fab")
			(hide yes)
			(effects
				(font
					(size 1 1)
					(thickness 0.15)
				)
			)
		)
		(sheetname "/Power Supply/")
		(sheetfile "supply.kicad_sch")
		(attr smd)
		(fp_line
			(start -1 -1.5)
			(end -1 -1.375)
			(stroke
				(width 0.15)
				(type solid)
			)
			(layer "F.SilkS")
		)
		(fp_line
			(start -1 1.55)
			(end -1 1.4)
			(stroke
				(width 0.15)
				(type solid)
			)
			(layer "F.SilkS")
		)
		(fp_line
			(start 1 -1.497)
			(end -1 -1.5)
			(stroke
				(width 0.15)
				(type solid)
			)
			(layer "F.SilkS")
		)
		(fp_line
			(start 1 -1.497)
			(end 1 -1.375)
			(stroke
				(width 0.15)
				(type solid)
			)
			(layer "F.SilkS")
		)
		(fp_line
			(start 1 1.55)
			(end -1 1.55)
			(stroke
				(width 0.15)
				(type solid)
			)
			(layer "F.SilkS")
		)
		(fp_line
			(start 1 1.55)
			(end 1 1.4)
			(stroke
				(width 0.15)
				(type solid)
			)
			(layer "F.SilkS")
		)
		(fp_circle
			(center -1.44 -1.5)
			(end -1.39 -1.5)
			(stroke
				(width 0.15)
				(type solid)
			)
			(fill yes)
			(layer "F.SilkS")
		)
		(fp_rect
			(start 1.93 -1.7)
			(end -1.93 1.7)
			(stroke
				(width 0.05)
				(type solid)
			)
			(fill no)
			(layer "F.CrtYd")
		)
		(fp_line
			(start -0.45 -1.521)
			(end -0.876 -1.096)
			(stroke
				(width 0.15)
				(type solid)
			)
			(layer "F.Fab")
		)
		(fp_rect
			(start 0.875 1.528)
			(end -0.875 -1.525)
			(stroke
				(width 0.15)
				(type solid)
			)
			(fill no)
			(layer "F.Fab")
		)
		(fp_text user "Author: Antmicro"
			(at -1.93 5 0)
			(layer "F.Fab")
			(effects
				(font
					(size 0.7 0.7)
					(thickness 0.15)
				)
				(justify left bottom)
			)
		)
		(fp_text user "${REFERENCE}"
			(at -1.93 3.8 0)
			(layer "F.Fab")
			(effects
				(font
					(size 0.7 0.7)
					(thickness 0.15)
				)
				(justify left bottom)
			)
		)
		(fp_text user "License: Apache-2.0"
			(at -1.93 6.199 0)
			(layer "F.Fab")
			(effects
				(font
					(size 0.7 0.7)
					(thickness 0.15)
				)
				(justify left bottom)
			)
		)
		(pad "1" smd rect
			(at -1.301 -0.947 270)
			(size 0.7 1.2)
			(layers "F.Cu" "F.Mask" "F.Paste")
			(net 1 "GND")
			(pinfunction "GND")
			(pintype "power_in")
		)
		(pad "2" smd rect
			(at -1.301 0.004 270)
			(size 0.7 1.2)
			(layers "F.Cu" "F.Mask" "F.Paste")
			(net 278 "/Power Supply/3V3_SW")
			(pinfunction "SW")
			(pintype "power_out")
		)
		(pad "3" smd rect
			(at -1.301 0.954 270)
			(size 0.7 1.2)
			(layers "F.Cu" "F.Mask" "F.Paste")
			(net 328 "/Power Supply/5V_3V3_IN")
			(pinfunction "VIN")
			(pintype "power_in")
		)
		(pad "4" smd rect
			(at 1.299 0.954 270)
			(size 0.7 1.2)
			(layers "F.Cu" "F.Mask" "F.Paste")
			(net 270 "Net-(U7-FB)")
			(pinfunction "FB")
			(pintype "input")
		)
		(pad "5" smd rect
			(at 1.299 0.004 270)
			(size 0.7 1.2)
			(layers "F.Cu" "F.Mask" "F.Paste")
			(net 375 "Net-(U7-EN)")
			(pinfunction "EN")
			(pintype "input")
		)
		(pad "6" smd rect
			(at 1.299 -0.947 270)
			(size 0.7 1.2)
			(layers "F.Cu" "F.Mask" "F.Paste")
			(net 140 "Net-(U7-BST)")
			(pinfunction "BST")
			(pintype "output")
		)
	)
	(footprint "antmicro-footprints:C_0603_1608Metric"
		(layer "F.Cu")
		(at 159.78 65.19 90)
		(descr "Capacitor SMD 0603")
		(tags "capacitor 0603")
		(property "Reference" "C25"
			(at -0.99 -0.7 90)
			(layer "F.SilkS")
			(effects
				(font
					(size 0.65 0.65)
					(thickness 0.15)
				)
				(justify left bottom)
			)
		)
		(property "Value" "C_22u_0603"
			(at 0 1.6 90)
			(layer "F.Fab")
			(hide yes)
			(effects
				(font
					(size 0.7 0.7)
					(thickness 0.15)
				)
				(justify left bottom)
			)
		)
		(property "Datasheet" "https://www.murata.com/products/productdetail?partno=GRM188R60J226MEA0%23"
			(at 0 0 90)
			(layer "F.Fab")
			(hide yes)
			(effects
				(font
					(size 1.27 1.27)
					(thickness 0.15)
				)
			)
		)
		(property "Description" "SMD Multilayer Ceramic Capacitor, 22 µF, 6.3 V, 0603 [1608 Metric], ± 20%, X5R, GRM Series"
			(at 0 0 90)
			(layer "F.Fab")
			(hide yes)
			(effects
				(font
					(size 1.27 1.27)
					(thickness 0.15)
				)
			)
		)
		(property "Author" "Antmicro"
			(at 224.97 -94.59 0)
			(layer "F.Fab")
			(hide yes)
			(effects
				(font
					(size 1 1)
					(thickness 0.15)
				)
			)
		)
		(property "Dielectric" ""
			(at 224.97 -94.59 0)
			(layer "F.Fab")
			(hide yes)
			(effects
				(font
					(size 1 1)
					(thickness 0.15)
				)
			)
		)
		(property "License" "Apache-2.0"
			(at 224.97 -94.59 0)
			(layer "F.Fab")
			(hide yes)
			(effects
				(font
					(size 1 1)
					(thickness 0.15)
				)
			)
		)
		(property "MPN" "GRM188R60J226MEA0D"
			(at 224.97 -94.59 0)
			(layer "F.Fab")
			(hide yes)
			(effects
				(font
					(size 1 1)
					(thickness 0.15)
				)
			)
		)
		(property "Manufacturer" "Murata"
			(at 224.97 -94.59 0)
			(layer "F.Fab")
			(hide yes)
			(effects
				(font
					(size 1 1)
					(thickness 0.15)
				)
			)
		)
		(property "Val" "22u"
			(at 224.97 -94.59 0)
			(layer "F.Fab")
			(hide yes)
			(effects
				(font
					(size 1 1)
					(thickness 0.15)
				)
			)
		)
		(property "Voltage" ""
			(at 224.97 -94.59 0)
			(layer "F.Fab")
			(hide yes)
			(effects
				(font
					(size 1 1)
					(thickness 0.15)
				)
			)
		)
		(sheetname "/Power Supply/")
		(sheetfile "supply.kicad_sch")
		(attr smd)
		(fp_line
			(start -0.15 -0.4)
			(end 0.15 -0.4)
			(stroke
				(width 0.15)
				(type solid)
			)
			(layer "F.SilkS")
		)
		(fp_line
			(start -0.15 0.4)
			(end 0.15 0.4)
			(stroke
				(width 0.15)
				(type solid)
			)
			(layer "F.SilkS")
		)
		(fp_rect
			(start -1.25 -0.65)
			(end 1.25 0.65)
			(stroke
				(width 0.05)
				(type solid)
			)
			(fill no)
			(layer "F.CrtYd")
		)
		(fp_rect
			(start -0.8 -0.4)
			(end 0.8 0.4)
			(stroke
				(width 0.15)
				(type solid)
			)
			(fill no)
			(layer "F.Fab")
		)
		(fp_text user "Author: Antmicro"
			(at -1.682 4.894 90)
			(layer "F.Fab")
			(effects
				(font
					(size 0.7 0.7)
					(thickness 0.15)
				)
				(justify left bottom)
			)
		)
		(fp_text user "License: Apache-2.0"
			(at -1.682 5.895 90)
			(layer "F.Fab")
			(effects
				(font
					(size 0.7 0.7)
					(thickness 0.15)
				)
				(justify left bottom)
			)
		)
		(fp_text user "${REFERENCE}"
			(at -1.682 3.895 90)
			(layer "F.Fab")
			(effects
				(font
					(size 0.7 0.7)
					(thickness 0.15)
				)
				(justify left bottom)
			)
		)
		(pad "1" smd roundrect
			(at -0.7 0 90)
			(size 0.8 1)
			(layers "F.Cu" "F.Mask" "F.Paste")
			(roundrect_rratio 0.2)
			(net 1 "GND")
			(pintype "passive")
		)
		(pad "2" smd roundrect
			(at 0.7 0 90)
			(size 0.8 1)
			(layers "F.Cu" "F.Mask" "F.Paste")
			(roundrect_rratio 0.2)
			(net 275 "/Power Supply/3V3_OUT")
			(pintype "passive")
		)
	)
	(footprint "antmicro-footprints:C_0603_1608Metric"
		(layer "F.Cu")
		(at 147.14 114.65 -90)
		(descr "Capacitor SMD 0603")
		(tags "capacitor 0603")
		(property "Reference" "C18"
			(at -1.51 -2.49 90)
			(layer "F.SilkS")
			(effects
				(font
					(size 0.65 0.65)
					(thickness 0.15)
				)
				(justify right bottom)
			)
		)
		(property "Value" "C_1u_0603"
			(at 0 1.6 90)
			(layer "F.Fab")
			(hide yes)
			(effects
				(font
					(size 0.7 0.7)
					(thickness 0.15)
				)
				(justify right bottom)
			)
		)
		(property "Datasheet" "https://spicat.kyocera-avx.com/product/mlcc/chartview/0603YD105KAT2A/"
			(at 0 0 270)
			(layer "F.Fab")
			(hide yes)
			(effects
				(font
					(size 1.27 1.27)
					(thickness 0.15)
				)
			)
		)
		(property "Description" "SMD Multilayer Ceramic Capacitor, 1 µF, 16 V, 0603 [1608 Metric], ± 10%, X5R, AVX 0603 MLCC"
			(at 0 0 270)
			(layer "F.Fab")
			(hide yes)
			(effects
				(font
					(size 1.27 1.27)
					(thickness 0.15)
				)
			)
		)
		(property "Author" "Antmicro"
			(at 32.49 261.79 0)
			(layer "F.Fab")
			(hide yes)
			(effects
				(font
					(size 1 1)
					(thickness 0.15)
				)
			)
		)
		(property "Dielectric" ""
			(at 32.49 261.79 0)
			(layer "F.Fab")
			(hide yes)
			(effects
				(font
					(size 1 1)
					(thickness 0.15)
				)
			)
		)
		(property "License" "Apache-2.0"
			(at 32.49 261.79 0)
			(layer "F.Fab")
			(hide yes)
			(effects
				(font
					(size 1 1)
					(thickness 0.15)
				)
			)
		)
		(property "MPN" "0603YD105KAT2A"
			(at 32.49 261.79 0)
			(layer "F.Fab")
			(hide yes)
			(effects
				(font
					(size 1 1)
					(thickness 0.15)
				)
			)
		)
		(property "Manufacturer" "KYOCERA AVX"
			(at 32.49 261.79 0)
			(layer "F.Fab")
			(hide yes)
			(effects
				(font
					(size 1 1)
					(thickness 0.15)
				)
			)
		)
		(property "Val" "1u"
			(at 32.49 261.79 0)
			(layer "F.Fab")
			(hide yes)
			(effects
				(font
					(size 1 1)
					(thickness 0.15)
				)
			)
		)
		(property "Voltage" ""
			(at 32.49 261.79 0)
			(layer "F.Fab")
			(hide yes)
			(effects
				(font
					(size 1 1)
					(thickness 0.15)
				)
			)
		)
		(sheetname "/Power Supply/")
		(sheetfile "supply.kicad_sch")
		(attr smd)
		(fp_line
			(start -0.15 0.4)
			(end 0.15 0.4)
			(stroke
				(width 0.15)
				(type solid)
			)
			(layer "F.SilkS")
		)
		(fp_line
			(start -0.15 -0.4)
			(end 0.15 -0.4)
			(stroke
				(width 0.15)
				(type solid)
			)
			(layer "F.SilkS")
		)
		(fp_rect
			(start -1.25 -0.65)
			(end 1.25 0.65)
			(stroke
				(width 0.05)
				(type solid)
			)
			(fill no)
			(layer "F.CrtYd")
		)
		(fp_rect
			(start -0.8 -0.4)
			(end 0.8 0.4)
			(stroke
				(width 0.15)
				(type solid)
			)
			(fill no)
			(layer "F.Fab")
		)
		(fp_text user "License: Apache-2.0"
			(at -1.682 5.895 270)
			(layer "F.Fab")
			(effects
				(font
					(size 0.7 0.7)
					(thickness 0.15)
				)
				(justify left bottom)
			)
		)
		(fp_text user "Author: Antmicro"
			(at -1.682 4.894 270)
			(layer "F.Fab")
			(effects
				(font
					(size 0.7 0.7)
					(thickness 0.15)
				)
				(justify left bottom)
			)
		)
		(fp_text user "${REFERENCE}"
			(at -1.682 3.895 270)
			(layer "F.Fab")
			(effects
				(font
					(size 0.7 0.7)
					(thickness 0.15)
				)
				(justify left bottom)
			)
		)
		(pad "1" smd roundrect
			(at -0.7 0 270)
			(size 0.8 1)
			(layers "F.Cu" "F.Mask" "F.Paste")
			(roundrect_rratio 0.2)
			(net 1 "GND")
			(pintype "passive")
		)
		(pad "2" smd roundrect
			(at 0.7 0 270)
			(size 0.8 1)
			(layers "F.Cu" "F.Mask" "F.Paste")
			(roundrect_rratio 0.2)
			(net 2 "+3V3")
			(pintype "passive")
		)
	)
)
